# T6G (Grand Teton) — schematic netlist excerpt (pin names and nets, part order shuffled) for the footprints in the layout excerpt that follows; sources: Cadence DE-HDL packaged netlist, KiCad conversion of 04192023_DAF0TMB3IC0_F0TG_MB_C_brd_V02_OCP.brd

R3689  Q_RES  4.7K 1% EMPTY  pkg 0402LF  page 257 : A = P3V3_ADC128_VCC ; B = ADC128_VREF
PC577_7  Q_CAP  0.1UF 25V 10% X7R  pkg 0402  page 198 : A = PVDDCR_CPU0_P0_VCCS ; B = GND

(kicad_pcb
	(version 20260206)
	(generator "pcbnew")
	(generator_version "10.0")
	(general
		(thickness 1.6)
		(legacy_teardrops no)
	)
	(paper "A4")
	(title_block
		(title "04192023_DAF0TMB3IC0_F0TG_MB_C_brd_V02_OCP.brd")
		(comment 1 "Grand Teton / footprints 2246-2247 of 8354")
	)
	(layers
		(0 "F.Cu" signal "TOP")
		(4 "In1.Cu" signal "GND")
		(6 "In2.Cu" signal "IN1")
		(8 "In3.Cu" signal "GND1")
		(10 "In4.Cu" signal "IN2")
		(12 "In5.Cu" signal "GND2")
		(14 "In6.Cu" signal "IN3")
		(16 "In7.Cu" signal "GND3")
		(18 "In8.Cu" signal "VCC")
		(20 "In9.Cu" signal "VCC1")
		(22 "In10.Cu" signal "GND4")
		(24 "In11.Cu" signal "IN4")
		(26 "In12.Cu" signal "GND5")
		(28 "In13.Cu" signal "IN5")
		(30 "In14.Cu" signal "GND6")
		(32 "In15.Cu" signal "IN6")
		(34 "In16.Cu" signal "GND7")
		(2 "B.Cu" signal "BOTTOM")
		(9 "F.Adhes" user "F.Adhesive")
		(11 "B.Adhes" user "B.Adhesive")
		(13 "F.Paste" user "Package Geometry/Pastemask Top")
		(15 "B.Paste" user "Package Geometry/Pastemask Bottom")
		(5 "F.SilkS" user "Ref Des/Silkscreen Top")
		(7 "B.SilkS" user "Ref Des/Silkscreen Bottom")
		(1 "F.Mask" user "Board Geometry/Soldermask Top")
		(3 "B.Mask" user "Board Geometry/Soldermask Bottom")
		(17 "Dwgs.User" user "User.Drawings")
		(19 "Cmts.User" user "User.Comments")
		(21 "Eco1.User" user "User.Eco1")
		(23 "Eco2.User" user "User.Eco2")
		(25 "Edge.Cuts" user "Board Geometry/Outline")
		(27 "Margin" user)
		(31 "F.CrtYd" user "Package Geometry/Place Bound Top")
		(29 "B.CrtYd" user "Package Geometry/Place Bound Bottom")
		(35 "F.Fab" user "Ref Des/Assembly Top")
		(33 "B.Fab" user "Ref Des/Assembly Bottom")
	)
	(footprint ""
		(layer "F.Cu")
		(at 305.826922 -47.991268)
		(property "Reference" "R3689"
			(at 0 0 0)
			(layer "F.SilkS")
			(hide yes)
			(effects
				(font
					(size 1.27 1.27)
				)
			)
		)
		(property "Value" ""
			(at 0 0 0)
			(layer "F.Fab")
			(effects
				(font
					(size 1.27 1.27)
				)
			)
		)
		(duplicate_pad_numbers_are_jumpers no)
		(fp_line
			(start -0.7874 -0.4064)
			(end 0.7874 -0.4064)
			(stroke
				(width 0.1524)
				(type default)
			)
			(layer "F.SilkS")
		)
		(fp_line
			(start -0.7874 0.4064)
			(end -0.7874 -0.4064)
			(stroke
				(width 0.1524)
				(type default)
			)
			(layer "F.SilkS")
		)
		(fp_line
			(start 0.7874 -0.4064)
			(end 0.7874 0.4064)
			(stroke
				(width 0.1524)
				(type default)
			)
			(layer "F.SilkS")
		)
		(fp_line
			(start 0.7874 0.4064)
			(end -0.7874 0.4064)
			(stroke
				(width 0.1524)
				(type default)
			)
			(layer "F.SilkS")
		)
		(fp_line
			(start -0.67945 -0.305054)
			(end -0.12065 -0.305054)
			(stroke
				(width 0.1)
				(type default)
			)
			(layer "F.Fab")
		)
		(fp_line
			(start -0.67945 0.3048)
			(end -0.67945 -0.305054)
			(stroke
				(width 0.1)
				(type default)
			)
			(layer "F.Fab")
		)
		(fp_line
			(start -0.12065 -0.305054)
			(end -0.12065 -0.2794)
			(stroke
				(width 0.1)
				(type default)
			)
			(layer "F.Fab")
		)
		(fp_line
			(start -0.12065 -0.2794)
			(end 0.12065 -0.2794)
			(stroke
				(width 0.1)
				(type default)
			)
			(layer "F.Fab")
		)
		(fp_line
			(start -0.12065 0.2794)
			(end -0.12065 0.3048)
			(stroke
				(width 0.1)
				(type default)
			)
			(layer "F.Fab")
		)
		(fp_line
			(start -0.12065 0.3048)
			(end -0.67945 0.3048)
			(stroke
				(width 0.1)
				(type default)
			)
			(layer "F.Fab")
		)
		(fp_line
			(start 0.120396 0.2794)
			(end -0.12065 0.2794)
			(stroke
				(width 0.1)
				(type default)
			)
			(layer "F.Fab")
		)
		(fp_line
			(start 0.120396 0.3048)
			(end 0.120396 0.2794)
			(stroke
				(width 0.1)
				(type default)
			)
			(layer "F.Fab")
		)
		(fp_line
			(start 0.12065 -0.3048)
			(end 0.67945 -0.3048)
			(stroke
				(width 0.1)
				(type default)
			)
			(layer "F.Fab")
		)
		(fp_line
			(start 0.12065 -0.2794)
			(end 0.12065 -0.3048)
			(stroke
				(width 0.1)
				(type default)
			)
			(layer "F.Fab")
		)
		(fp_line
			(start 0.67945 -0.3048)
			(end 0.67945 0.3048)
			(stroke
				(width 0.1)
				(type default)
			)
			(layer "F.Fab")
		)
		(fp_line
			(start 0.67945 0.3048)
			(end 0.120396 0.3048)
			(stroke
				(width 0.1)
				(type default)
			)
			(layer "F.Fab")
		)
		(pad "1" smd circle
			(at -0.40005 0)
			(size 0 0)
			(layers "F.Cu" "F.Mask" "F.Paste")
			(net "P3V3_ADC128_VCC")
		)
		(pad "2" smd circle
			(at 0.40005 0)
			(size 0 0)
			(layers "F.Cu" "F.Mask" "F.Paste")
			(net "ADC128_VREF")
		)
	)
	(footprint ""
		(layer "F.Cu")
		(at 400.518122 -172.3136 -90)
		(property "Reference" "PC577_7"
			(at 0 0 270)
			(layer "F.SilkS")
			(hide yes)
			(effects
				(font
					(size 1.27 1.27)
				)
			)
		)
		(property "Value" ""
			(at 0 0 270)
			(layer "F.Fab")
			(effects
				(font
					(size 1.27 1.27)
				)
			)
		)
		(duplicate_pad_numbers_are_jumpers no)
		(fp_line
			(start -0.7874 0.4064)
			(end -0.7874 -0.4064)
			(stroke
				(width 0.1524)
				(type default)
			)
			(layer "F.SilkS")
		)
		(fp_line
			(start 0.7874 0.4064)
			(end -0.7874 0.4064)
			(stroke
				(width 0.1524)
				(type default)
			)
			(layer "F.SilkS")
		)
		(fp_line
			(start -0.7874 -0.4064)
			(end 0.7874 -0.4064)
			(stroke
				(width 0.1524)
				(type default)
			)
			(layer "F.SilkS")
		)
		(fp_line
			(start 0.7874 -0.4064)
			(end 0.7874 0.4064)
			(stroke
				(width 0.1524)
				(type default)
			)
			(layer "F.SilkS")
		)
		(fp_line
			(start -0.67945 0.3048)
			(end -0.67945 -0.305054)
			(stroke
				(width 0.1)
				(type default)
			)
			(layer "F.Fab")
		)
		(fp_line
			(start -0.12065 0.3048)
			(end -0.67945 0.3048)
			(stroke
				(width 0.1)
				(type default)
			)
			(layer "F.Fab")
		)
		(fp_line
			(start 0.120396 0.3048)
			(end 0.120396 0.2794)
			(stroke
				(width 0.1)
				(type default)
			)
			(layer "F.Fab")
		)
		(fp_line
			(start 0.67945 0.3048)
			(end 0.120396 0.3048)
			(stroke
				(width 0.1)
				(type default)
			)
			(layer "F.Fab")
		)
		(fp_line
			(start -0.12065 0.2794)
			(end -0.12065 0.3048)
			(stroke
				(width 0.1)
				(type default)
			)
			(layer "F.Fab")
		)
		(fp_line
			(start 0.120396 0.2794)
			(end -0.12065 0.2794)
			(stroke
				(width 0.1)
				(type default)
			)
			(layer "F.Fab")
		)
		(fp_line
			(start -0.12065 -0.2794)
			(end 0.12065 -0.2794)
			(stroke
				(width 0.1)
				(type default)
			)
			(layer "F.Fab")
		)
		(fp_line
			(start 0.12065 -0.2794)
			(end 0.12065 -0.3048)
			(stroke
				(width 0.1)
				(type default)
			)
			(layer "F.Fab")
		)
		(fp_line
			(start 0.12065 -0.3048)
			(end 0.67945 -0.3048)
			(stroke
				(width 0.1)
				(type default)
			)
			(layer "F.Fab")
		)
		(fp_line
			(start 0.67945 -0.3048)
			(end 0.67945 0.3048)
			(stroke
				(width 0.1)
				(type default)
			)
			(layer "F.Fab")
		)
		(fp_line
			(start -0.67945 -0.305054)
			(end -0.12065 -0.305054)
			(stroke
				(width 0.1)
				(type default)
			)
			(layer "F.Fab")
		)
		(fp_line
			(start -0.12065 -0.305054)
			(end -0.12065 -0.2794)
			(stroke
				(width 0.1)
				(type default)
			)
			(layer "F.Fab")
		)
		(pad "1" smd circle
			(at -0.40005 0 270)
			(size 0 0)
			(layers "F.Cu" "F.Mask" "F.Paste")
			(net "PVDDCR_CPU0_P0_VCCS")
		)
		(pad "2" smd circle
			(at 0.40005 0 270)
			(size 0 0)
			(layers "F.Cu" "F.Mask" "F.Paste")
			(net "GND")
		)
	)
)
